(kicad_pcb
	(version 20260206)
	(generator "pcbnew")
	(generator_version "10.0")
	(general
		(thickness 1.6)
		(legacy_teardrops no)
	)
	(paper "A4")
	(title_block
		(title "panther-plus-userver — 13130-1b_20150205.brd")
		(comment 1 "Honey Badger (Wiwynn) / footprints 1489-1496 of 1509")
	)
	(layers
		(0 "F.Cu" signal "TOP")
		(4 "In1.Cu" signal "L2")
		(6 "In2.Cu" signal "L3")
		(8 "In3.Cu" signal "L4")
		(10 "In4.Cu" signal "L5")
		(12 "In5.Cu" signal "L6")
		(14 "In6.Cu" signal "L7")
		(16 "In7.Cu" signal "L8")
		(18 "In8.Cu" signal "L9")
		(20 "In9.Cu" signal "L10")
		(22 "In10.Cu" signal "L11")
		(2 "B.Cu" signal "BOTTOM")
		(9 "F.Adhes" user "F.Adhesive")
		(11 "B.Adhes" user "B.Adhesive")
		(13 "F.Paste" user "Package Geometry/Pastemask Top")
		(15 "B.Paste" user "Package Geometry/Pastemask Bottom")
		(5 "F.SilkS" user "Ref Des/Silkscreen Top")
		(7 "B.SilkS" user "Ref Des/Silkscreen Bottom")
		(1 "F.Mask" user "Board Geometry/Soldermask Top")
		(3 "B.Mask" user "Board Geometry/Soldermask Bottom")
		(17 "Dwgs.User" user "User.Drawings")
		(19 "Cmts.User" user "User.Comments")
		(21 "Eco1.User" user "User.Eco1")
		(23 "Eco2.User" user "User.Eco2")
		(25 "Edge.Cuts" user "Board Geometry/Outline")
		(27 "Margin" user)
		(31 "F.CrtYd" user "Package Geometry/Place Bound Top")
		(29 "B.CrtYd" user "Package Geometry/Place Bound Bottom")
		(35 "F.Fab" user "Ref Des/Assembly Top")
		(33 "B.Fab" user "Ref Des/Assembly Bottom")
	)
	(footprint ""
		(layer "B.Cu")
		(at 95.5802 -40.8686 -90)
		(property "Reference" "TP28"
			(at 0 0 90)
			(layer "B.SilkS")
			(hide yes)
			(effects
				(font
					(size 1.27 1.27)
				)
				(justify mirror)
			)
		)
		(property "Value" "TPAD24"
			(at 0 -2.9972 270)
			(unlocked yes)
			(layer "B.Fab")
			(hide yes)
			(effects
				(font
					(size 1.016 1.016)
					(thickness 0.1524)
				)
				(justify mirror)
			)
		)
		(property "Device Type" "TPAD24"
			(at 0 -4.5212 270)
			(unlocked yes)
			(layer "B.Fab")
			(hide yes)
			(effects
				(font
					(size 1.016 1.016)
					(thickness 0.1524)
				)
				(justify mirror)
			)
		)
		(duplicate_pad_numbers_are_jumpers no)
		(fp_poly
			(pts
				(arc
					(start 0 -0.3048)
					(mid 0 0.3048)
					(end 0 -0.3048)
				)
			)
			(stroke
				(width 0)
				(type default)
			)
			(fill no)
			(layer "B.CrtYd")
		)
		(fp_poly
			(pts
				(arc
					(start 0 -0.6096)
					(mid 0 0.6096)
					(end 0 -0.6096)
				)
			)
			(stroke
				(width 0)
				(type default)
			)
			(fill no)
			(layer "B.Fab")
		)
		(pad "1" smd circle
			(at 0 0 90)
			(size 0.6096 0.6096)
			(layers "B.Cu" "B.Mask" "B.Paste")
			(net "VCCCORE6VIDSI0GT_1P03")
		)
	)
	(footprint ""
		(layer "B.Cu")
		(at 25.4 -46.101 -90)
		(property "Reference" "PC133"
			(at 0 0 90)
			(layer "B.SilkS")
			(hide yes)
			(effects
				(font
					(size 1.27 1.27)
				)
				(justify mirror)
			)
		)
		(property "Value" "SC10U6D3V5KX-4GP"
			(at 0 -4.9022 270)
			(unlocked yes)
			(layer "B.Fab")
			(hide yes)
			(effects
				(font
					(size 1.016 1.016)
					(thickness 0.1524)
				)
				(justify mirror)
			)
		)
		(property "Device Type" "C805H58"
			(at 0 -6.8072 270)
			(unlocked yes)
			(layer "B.Fab")
			(hide yes)
			(effects
				(font
					(size 1.016 1.016)
					(thickness 0.1524)
				)
				(justify mirror)
			)
		)
		(duplicate_pad_numbers_are_jumpers no)
		(fp_line
			(start -0.6096 0)
			(end 0.6096 0)
			(stroke
				(width 0.3048)
				(type default)
			)
			(layer "B.SilkS")
		)
		(fp_poly
			(pts
				(xy 0.9017 1.4351) (xy -0.9017 1.4351) (xy -0.9017 -1.4351) (xy 0.9017 -1.4351)
			)
			(stroke
				(width 0)
				(type default)
			)
			(fill no)
			(layer "B.CrtYd")
		)
		(fp_poly
			(pts
				(xy -0.9017 1.4351) (xy -0.9017 -1.4351) (xy 0.9017 -1.4351) (xy 0.9017 1.4351)
			)
			(stroke
				(width 0)
				(type default)
			)
			(fill no)
			(layer "B.Fab")
		)
		(pad "1" smd rect
			(at 0 -0.8382 90)
			(size 1.5494 0.9398)
			(layers "B.Cu" "B.Mask" "B.Paste")
			(net "P1V5_STBY_OUT")
		)
		(pad "2" smd rect
			(at 0 0.8382 90)
			(size 1.5494 0.9398)
			(layers "B.Cu" "B.Mask" "B.Paste")
			(net "GND")
		)
	)
	(footprint ""
		(layer "B.Cu")
		(at 104.14 -27.321002)
		(property "Reference" "C242"
			(at 0 0 0)
			(layer "B.SilkS")
			(hide yes)
			(effects
				(font
					(size 1.27 1.27)
				)
				(justify mirror)
			)
		)
		(property "Value" "SC1U10V2KX-1GP"
			(at -1.1811 -2.7051 0)
			(unlocked yes)
			(layer "B.Fab")
			(hide yes)
			(effects
				(font
					(size 1.016 1.016)
					(thickness 0.1524)
				)
				(justify mirror)
			)
		)
		(property "Device Type" "C402H22"
			(at -1.1811 -4.2291 0)
			(unlocked yes)
			(layer "B.Fab")
			(hide yes)
			(effects
				(font
					(size 1.016 1.016)
					(thickness 0.1524)
				)
				(justify mirror)
			)
		)
		(duplicate_pad_numbers_are_jumpers no)
		(fp_rect
			(start 0.381 0.7366)
			(end -0.381 -0.7366)
			(stroke
				(width 0)
				(type default)
			)
			(fill no)
			(layer "B.CrtYd")
		)
		(fp_rect
			(start 0.381 0.7366)
			(end -0.381 -0.7366)
			(stroke
				(width 0)
				(type default)
			)
			(fill no)
			(layer "B.Fab")
		)
		(pad "1" smd custom
			(at 0 -0.4572 180)
			(size 0.1143 0.1143)
			(layers "B.Cu" "B.Mask" "B.Paste")
			(net "PV_VDDR")
			(options
				(clearance outline)
				(anchor circle)
			)
			(primitives
				(gr_poly
					(pts
						(arc
							(start -0.254 0.1778)
							(mid -0.239121 0.213721)
							(end -0.2032 0.2286)
						)
						(arc
							(start 0.2032 0.2286)
							(mid 0.239121 0.213721)
							(end 0.254 0.1778)
						)
						(arc
							(start 0.254 -0.1778)
							(mid 0.239121 -0.213721)
							(end 0.2032 -0.2286)
						)
						(arc
							(start -0.2032 -0.2286)
							(mid -0.239121 -0.213721)
							(end -0.254 -0.1778)
						)
					)
					(width 0)
					(fill yes)
				)
			)
		)
		(pad "2" smd custom
			(at 0 0.4572 180)
			(size 0.1143 0.1143)
			(layers "B.Cu" "B.Mask" "B.Paste")
			(net "GND")
			(options
				(clearance outline)
				(anchor circle)
			)
			(primitives
				(gr_poly
					(pts
						(arc
							(start -0.254 0.1778)
							(mid -0.239121 0.213721)
							(end -0.2032 0.2286)
						)
						(arc
							(start 0.2032 0.2286)
							(mid 0.239121 0.213721)
							(end 0.254 0.1778)
						)
						(arc
							(start 0.254 -0.1778)
							(mid 0.239121 -0.213721)
							(end 0.2032 -0.2286)
						)
						(arc
							(start -0.2032 -0.2286)
							(mid -0.239121 -0.213721)
							(end -0.254 -0.1778)
						)
					)
					(width 0)
					(fill yes)
				)
			)
		)
	)
	(footprint ""
		(layer "B.Cu")
		(at 94.615 -37.084 90)
		(property "Reference" "C187"
			(at 0 0 90)
			(layer "B.SilkS")
			(hide yes)
			(effects
				(font
					(size 1.27 1.27)
				)
				(justify mirror)
			)
		)
		(property "Value" "SC1U10V2KX-1GP"
			(at -1.1811 -2.7051 90)
			(unlocked yes)
			(layer "B.Fab")
			(hide yes)
			(effects
				(font
					(size 1.016 1.016)
					(thickness 0.1524)
				)
				(justify mirror)
			)
		)
		(property "Device Type" "C402H22"
			(at -1.1811 -4.2291 90)
			(unlocked yes)
			(layer "B.Fab")
			(hide yes)
			(effects
				(font
					(size 1.016 1.016)
					(thickness 0.1524)
				)
				(justify mirror)
			)
		)
		(duplicate_pad_numbers_are_jumpers no)
		(fp_rect
			(start 0.381 0.7366)
			(end -0.381 -0.7366)
			(stroke
				(width 0)
				(type default)
			)
			(fill no)
			(layer "B.CrtYd")
		)
		(fp_rect
			(start 0.381 0.7366)
			(end -0.381 -0.7366)
			(stroke
				(width 0)
				(type default)
			)
			(fill no)
			(layer "B.Fab")
		)
		(pad "1" smd custom
			(at 0 -0.4572 270)
			(size 0.1143 0.1143)
			(layers "B.Cu" "B.Mask" "B.Paste")
			(net "PVNN")
			(options
				(clearance outline)
				(anchor circle)
			)
			(primitives
				(gr_poly
					(pts
						(arc
							(start -0.254 0.1778)
							(mid -0.239121 0.213721)
							(end -0.2032 0.2286)
						)
						(arc
							(start 0.2032 0.2286)
							(mid 0.239121 0.213721)
							(end 0.254 0.1778)
						)
						(arc
							(start 0.254 -0.1778)
							(mid 0.239121 -0.213721)
							(end 0.2032 -0.2286)
						)
						(arc
							(start -0.2032 -0.2286)
							(mid -0.239121 -0.213721)
							(end -0.254 -0.1778)
						)
					)
					(width 0)
					(fill yes)
				)
			)
		)
		(pad "2" smd custom
			(at 0 0.4572 270)
			(size 0.1143 0.1143)
			(layers "B.Cu" "B.Mask" "B.Paste")
			(net "GND")
			(options
				(clearance outline)
				(anchor circle)
			)
			(primitives
				(gr_poly
					(pts
						(arc
							(start -0.254 0.1778)
							(mid -0.239121 0.213721)
							(end -0.2032 0.2286)
						)
						(arc
							(start 0.2032 0.2286)
							(mid 0.239121 0.213721)
							(end 0.254 0.1778)
						)
						(arc
							(start 0.254 -0.1778)
							(mid 0.239121 -0.213721)
							(end 0.2032 -0.2286)
						)
						(arc
							(start -0.2032 -0.2286)
							(mid -0.239121 -0.213721)
							(end -0.254 -0.1778)
						)
					)
					(width 0)
					(fill yes)
				)
			)
		)
	)
	(footprint ""
		(layer "B.Cu")
		(at 197.993 -43.434 -90)
		(property "Reference" "R156"
			(at 0 0 90)
			(layer "B.SilkS")
			(hide yes)
			(effects
				(font
					(size 1.27 1.27)
				)
				(justify mirror)
			)
		)
		(property "Value" "300R2F-GP"
			(at -0.064008 -3.993896 270)
			(unlocked yes)
			(layer "B.Fab")
			(hide yes)
			(effects
				(font
					(size 1.016 1.016)
					(thickness 0.1524)
				)
				(justify mirror)
			)
		)
		(property "Device Type" "R402H16"
			(at -0.064008 -5.517896 270)
			(unlocked yes)
			(layer "B.Fab")
			(hide yes)
			(effects
				(font
					(size 1.016 1.016)
					(thickness 0.1524)
				)
				(justify mirror)
			)
		)
		(duplicate_pad_numbers_are_jumpers no)
		(fp_rect
			(start 0.381 0.8382)
			(end -0.381 -0.8382)
			(stroke
				(width 0)
				(type default)
			)
			(fill no)
			(layer "B.CrtYd")
		)
		(fp_rect
			(start 0.381 0.8382)
			(end -0.381 -0.8382)
			(stroke
				(width 0)
				(type default)
			)
			(fill no)
			(layer "B.Fab")
		)
		(pad "1" smd custom
			(at 0 -0.4318 90)
			(size 0.127 0.127)
			(layers "B.Cu" "B.Mask" "B.Paste")
			(net "PORT80_R_BIT7")
			(options
				(clearance outline)
				(anchor circle)
			)
			(primitives
				(gr_poly
					(pts
						(arc
							(start -0.2032 0.2794)
							(mid -0.239121 0.264521)
							(end -0.254 0.2286)
						)
						(arc
							(start -0.254 -0.2286)
							(mid -0.239121 -0.264521)
							(end -0.2032 -0.2794)
						)
						(arc
							(start 0.2032 -0.2794)
							(mid 0.239121 -0.264521)
							(end 0.254 -0.2286)
						)
						(arc
							(start 0.254 0.2286)
							(mid 0.239121 0.264521)
							(end 0.2032 0.2794)
						)
					)
					(width 0)
					(fill yes)
				)
			)
		)
		(pad "2" smd custom
			(at 0 0.4318 90)
			(size 0.127 0.127)
			(layers "B.Cu" "B.Mask" "B.Paste")
			(net "P3V3_STBY")
			(options
				(clearance outline)
				(anchor circle)
			)
			(primitives
				(gr_poly
					(pts
						(arc
							(start -0.2032 0.2794)
							(mid -0.239121 0.264521)
							(end -0.254 0.2286)
						)
						(arc
							(start -0.254 -0.2286)
							(mid -0.239121 -0.264521)
							(end -0.2032 -0.2794)
						)
						(arc
							(start 0.2032 -0.2794)
							(mid 0.239121 -0.264521)
							(end 0.254 -0.2286)
						)
						(arc
							(start 0.254 0.2286)
							(mid 0.239121 0.264521)
							(end 0.2032 0.2794)
						)
					)
					(width 0)
					(fill yes)
				)
			)
		)
	)
	(footprint ""
		(layer "B.Cu")
		(at 69.088 -37.846 180)
		(property "Reference" "U15"
			(at 0 0 0)
			(layer "B.SilkS")
			(hide yes)
			(effects
				(font
					(size 1.27 1.27)
				)
				(justify mirror)
			)
		)
		(property "Value" "74LVC1G08GW-1-GP"
			(at 2.3368 -8.6868 180)
			(unlocked yes)
			(layer "B.Fab")
			(hide yes)
			(effects
				(font
					(size 1.016 1.016)
					(thickness 0.1524)
				)
				(justify mirror)
			)
		)
		(property "Device Type" "SC70-5H44"
			(at 2.3114 -10.414 180)
			(unlocked yes)
			(layer "B.Fab")
			(hide yes)
			(effects
				(font
					(size 1.016 1.016)
					(thickness 0.1524)
				)
				(justify mirror)
			)
		)
		(duplicate_pad_numbers_are_jumpers no)
		(fp_line
			(start 1.0033 0.3302)
			(end 1.0033 -0.3302)
			(stroke
				(width 0.1524)
				(type default)
			)
			(layer "B.SilkS")
		)
		(fp_line
			(start 1.0033 -0.3302)
			(end -1.0033 -0.3302)
			(stroke
				(width 0.1524)
				(type default)
			)
			(layer "B.SilkS")
		)
		(fp_line
			(start -1.0033 0.3302)
			(end 1.0033 0.3302)
			(stroke
				(width 0.1524)
				(type default)
			)
			(layer "B.SilkS")
		)
		(fp_line
			(start -1.0033 -0.3302)
			(end -1.0033 0.3302)
			(stroke
				(width 0.1524)
				(type default)
			)
			(layer "B.SilkS")
		)
		(fp_poly
			(pts
				(xy 1.0033 1.4859) (xy 1.0033 0.8001) (xy 1.1811 0.8001) (xy 1.1811 -0.8001) (xy 1.0033 -0.8001)
				(xy 1.0033 -1.4859) (xy -1.0033 -1.4859) (xy -1.0033 -0.8001) (xy -1.1811 -0.8001) (xy -1.1811 0.8001)
				(xy -1.0033 0.8001) (xy -1.0033 1.4859) (xy -0.2921 1.4859) (xy -0.2921 0.8001) (xy 0.2921 0.8001)
				(xy 0.2921 1.4859)
			)
			(stroke
				(width 0)
				(type default)
			)
			(fill no)
			(layer "B.CrtYd")
		)
		(fp_poly
			(pts
				(xy 1.0033 1.4859) (xy 1.0033 0.8001) (xy 1.1811 0.8001) (xy 1.1811 -0.8001) (xy 1.0033 -0.8001)
				(xy 1.0033 -1.4859) (xy -1.0033 -1.4859) (xy -1.0033 -0.8001) (xy -1.1811 -0.8001) (xy -1.1811 0.8001)
				(xy -1.0033 0.8001) (xy -1.0033 1.4859) (xy -0.2921 1.4859) (xy -0.2921 0.8001) (xy 0.2921 0.8001)
				(xy 0.2921 1.4859)
			)
			(stroke
				(width 0)
				(type default)
			)
			(fill no)
			(layer "B.Fab")
		)
		(pad "1" smd rect
			(at -0.65024 -0.93472)
			(size 0.3556 0.762)
			(layers "B.Cu" "B.Mask" "B.Paste")
			(net "PMU_SLP_INB_S3#")
		)
		(pad "2" smd rect
			(at 0 -0.93472)
			(size 0.3556 0.762)
			(layers "B.Cu" "B.Mask" "B.Paste")
			(net "PMU_SLP_INA_DDRVTT#")
		)
		(pad "3" smd rect
			(at 0.65024 -0.93472)
			(size 0.3556 0.762)
			(layers "B.Cu" "B.Mask" "B.Paste")
			(net "GND")
		)
		(pad "4" smd rect
			(at 0.65024 0.93472)
			(size 0.3556 0.762)
			(layers "B.Cu" "B.Mask" "B.Paste")
			(net "PVTT_DDR_EN")
		)
		(pad "5" smd rect
			(at -0.65024 0.93472)
			(size 0.3556 0.762)
			(layers "B.Cu" "B.Mask" "B.Paste")
			(net "P3V3_STBY")
		)
	)
	(footprint ""
		(layer "B.Cu")
		(at 6.604 -32.131)
		(property "Reference" "PR204"
			(at 0 0 0)
			(layer "B.SilkS")
			(hide yes)
			(effects
				(font
					(size 1.27 1.27)
				)
				(justify mirror)
			)
		)
		(property "Value" "475KR2F-GP"
			(at -1.7907 -1.1176 0)
			(unlocked yes)
			(layer "B.Fab")
			(hide yes)
			(effects
				(font
					(size 1.016 1.016)
					(thickness 0.1524)
				)
				(justify mirror)
			)
		)
		(property "Device Type" "R402H16"
			(at -1.7907 -2.6416 0)
			(unlocked yes)
			(layer "B.Fab")
			(hide yes)
			(effects
				(font
					(size 1.016 1.016)
					(thickness 0.1524)
				)
				(justify mirror)
			)
		)
		(duplicate_pad_numbers_are_jumpers no)
		(fp_rect
			(start 0.381 0.8382)
			(end -0.381 -0.8382)
			(stroke
				(width 0)
				(type default)
			)
			(fill no)
			(layer "B.CrtYd")
		)
		(fp_rect
			(start 0.381 0.8382)
			(end -0.381 -0.8382)
			(stroke
				(width 0)
				(type default)
			)
			(fill no)
			(layer "B.Fab")
		)
		(pad "1" smd custom
			(at 0 -0.4318 180)
			(size 0.127 0.127)
			(layers "B.Cu" "B.Mask" "B.Paste")
			(net "P3V3_STBY_MODE")
			(options
				(clearance outline)
				(anchor circle)
			)
			(primitives
				(gr_poly
					(pts
						(arc
							(start -0.2032 0.2794)
							(mid -0.239121 0.264521)
							(end -0.254 0.2286)
						)
						(arc
							(start -0.254 -0.2286)
							(mid -0.239121 -0.264521)
							(end -0.2032 -0.2794)
						)
						(arc
							(start 0.2032 -0.2794)
							(mid 0.239121 -0.264521)
							(end 0.254 -0.2286)
						)
						(arc
							(start 0.254 0.2286)
							(mid 0.239121 0.264521)
							(end 0.2032 0.2794)
						)
					)
					(width 0)
					(fill yes)
				)
			)
		)
		(pad "2" smd custom
			(at 0 0.4318 180)
			(size 0.127 0.127)
			(layers "B.Cu" "B.Mask" "B.Paste")
			(net "P3V3_STBY_PG")
			(options
				(clearance outline)
				(anchor circle)
			)
			(primitives
				(gr_poly
					(pts
						(arc
							(start -0.2032 0.2794)
							(mid -0.239121 0.264521)
							(end -0.254 0.2286)
						)
						(arc
							(start -0.254 -0.2286)
							(mid -0.239121 -0.264521)
							(end -0.2032 -0.2794)
						)
						(arc
							(start 0.2032 -0.2794)
							(mid 0.239121 -0.264521)
							(end 0.254 -0.2286)
						)
						(arc
							(start 0.254 0.2286)
							(mid 0.239121 0.264521)
							(end 0.2032 0.2794)
						)
					)
					(width 0)
					(fill yes)
				)
			)
		)
	)
	(footprint ""
		(layer "B.Cu")
		(at 189.357 -27.94 180)
		(property "Reference" "PR216"
			(at 0 0 0)
			(layer "B.SilkS")
			(hide yes)
			(effects
				(font
					(size 1.27 1.27)
				)
				(justify mirror)
			)
		)
		(property "Value" "10KR2F-2-GP"
			(at -1.7907 -1.1176 180)
			(unlocked yes)
			(layer "B.Fab")
			(hide yes)
			(effects
				(font
					(size 1.016 1.016)
					(thickness 0.1524)
				)
				(justify mirror)
			)
		)
		(property "Device Type" "R402H16"
			(at -1.7907 -2.6416 180)
			(unlocked yes)
			(layer "B.Fab")
			(hide yes)
			(effects
				(font
					(size 1.016 1.016)
					(thickness 0.1524)
				)
				(justify mirror)
			)
		)
		(duplicate_pad_numbers_are_jumpers no)
		(fp_rect
			(start 0.381 0.8382)
			(end -0.381 -0.8382)
			(stroke
				(width 0)
				(type default)
			)
			(fill no)
			(layer "B.CrtYd")
		)
		(fp_rect
			(start 0.381 0.8382)
			(end -0.381 -0.8382)
			(stroke
				(width 0)
				(type default)
			)
			(fill no)
			(layer "B.Fab")
		)
		(pad "1" smd custom
			(at 0 -0.4318)
			(size 0.127 0.127)
			(layers "B.Cu" "B.Mask" "B.Paste")
			(net "VR_PVDDRA_ISUMP1_R")
			(options
				(clearance outline)
				(anchor circle)
			)
			(primitives
				(gr_poly
					(pts
						(arc
							(start -0.2032 0.2794)
							(mid -0.239121 0.264521)
							(end -0.254 0.2286)
						)
						(arc
							(start -0.254 -0.2286)
							(mid -0.239121 -0.264521)
							(end -0.2032 -0.2794)
						)
						(arc
							(start 0.2032 -0.2794)
							(mid 0.239121 -0.264521)
							(end 0.254 -0.2286)
						)
						(arc
							(start 0.254 0.2286)
							(mid 0.239121 0.264521)
							(end 0.2032 0.2794)
						)
					)
					(width 0)
					(fill yes)
				)
			)
		)
		(pad "2" smd custom
			(at 0 0.4318)
			(size 0.127 0.127)
			(layers "B.Cu" "B.Mask" "B.Paste")
			(net "VR_PVDDRA_ISUMN1")
			(options
				(clearance outline)
				(anchor circle)
			)
			(primitives
				(gr_poly
					(pts
						(arc
							(start -0.2032 0.2794)
							(mid -0.239121 0.264521)
							(end -0.254 0.2286)
						)
						(arc
							(start -0.254 -0.2286)
							(mid -0.239121 -0.264521)
							(end -0.2032 -0.2794)
						)
						(arc
							(start 0.2032 -0.2794)
							(mid 0.239121 -0.264521)
							(end 0.254 -0.2286)
						)
						(arc
							(start 0.254 0.2286)
							(mid 0.239121 0.264521)
							(end 0.2032 0.2794)
						)
					)
					(width 0)
					(fill yes)
				)
			)
		)
	)
)
